# S9S_MB_2U (Grand Teton) — schematic netlist excerpt (pin names and nets, part order shuffled) for the footprints in the layout excerpt that follows; sources: Cadence DE-HDL packaged netlist, KiCad conversion of 03242023_DA0F0TMBIJ0_F0T_Motherboard_J_brd_V01_OCP.brd

R2909  Q_RES  4.7K 5% CHIP  pkg 0402LF  page 151 : A = P3V3_AUX ; B = RST_SWB_BIC_R_N
R4168  Q_RES  4.7K 5% CHIP  pkg 0402LF  page 145 : A = P3V3_AUX ; B = GPU_3V3IO_RSVD4_ISO
C704  Q_CAP_DIFFBUS  DIFF BUS_0.22UF 6.3V 20% X6S  pkg C0201  page 177 : \1\ = P5E_CPU1_PE4_TX_C_DN<2> ; \2\ = P5E_CPU1_PE4_TX_DN<2>
H102  HOLE  EMPTY  pkg TH  page 311 : \1\ = GND

(kicad_pcb
	(version 20260206)
	(generator "pcbnew")
	(generator_version "10.0")
	(general
		(thickness 1.6)
		(legacy_teardrops no)
	)
	(paper "A4")
	(title_block
		(title "03242023_DA0F0TMBIJ0_F0T_Motherboard_J_brd_V01_OCP.brd")
		(comment 1 "Grand Teton / footprints 989-992 of 6105")
	)
	(layers
		(0 "F.Cu" signal "TOP")
		(4 "In1.Cu" signal "GND")
		(6 "In2.Cu" signal "IN1")
		(8 "In3.Cu" signal "GND1")
		(10 "In4.Cu" signal "IN2")
		(12 "In5.Cu" signal "GND2")
		(14 "In6.Cu" signal "IN3")
		(16 "In7.Cu" signal "GND3")
		(18 "In8.Cu" signal "VCC")
		(20 "In9.Cu" signal "VCC1")
		(22 "In10.Cu" signal "GND4")
		(24 "In11.Cu" signal "IN4")
		(26 "In12.Cu" signal "GND5")
		(28 "In13.Cu" signal "IN5")
		(30 "In14.Cu" signal "GND6")
		(32 "In15.Cu" signal "IN6")
		(34 "In16.Cu" signal "GND7")
		(2 "B.Cu" signal "BOTTOM")
		(9 "F.Adhes" user "F.Adhesive")
		(11 "B.Adhes" user "B.Adhesive")
		(13 "F.Paste" user "Package Geometry/Pastemask Top")
		(15 "B.Paste" user "Package Geometry/Pastemask Bottom")
		(5 "F.SilkS" user "Ref Des/Silkscreen Top")
		(7 "B.SilkS" user "Ref Des/Silkscreen Bottom")
		(1 "F.Mask" user "Board Geometry/Soldermask Top")
		(3 "B.Mask" user "Board Geometry/Soldermask Bottom")
		(17 "Dwgs.User" user "User.Drawings")
		(19 "Cmts.User" user "User.Comments")
		(21 "Eco1.User" user "User.Eco1")
		(23 "Eco2.User" user "User.Eco2")
		(25 "Edge.Cuts" user "Board Geometry/Outline")
		(27 "Margin" user)
		(31 "F.CrtYd" user "Package Geometry/Place Bound Top")
		(29 "B.CrtYd" user "Package Geometry/Place Bound Bottom")
		(35 "F.Fab" user "Ref Des/Assembly Top")
		(33 "B.Fab" user "Ref Des/Assembly Bottom")
	)
	(footprint ""
		(layer "F.Cu")
		(at 265.64971 -22.29993)
		(property "Reference" "H102"
			(at -4.51104 -5.629148 0)
			(unlocked yes)
			(layer "F.SilkS")
			(effects
				(font
					(size 0.7874 0.5842)
					(thickness 0.1524)
				)
				(justify left)
			)
		)
		(property "Value" ""
			(at 0 0 0)
			(layer "F.Fab")
			(effects
				(font
					(size 1.27 1.27)
				)
			)
		)
		(duplicate_pad_numbers_are_jumpers no)
		(pad "1" thru_hole circle
			(at 0 0)
			(size 10.0076 10.0076)
			(drill 5.6134)
			(layers "*.Cu" "*.Mask")
			(remove_unused_layers no)
			(net "GND")
			(clearance -1.9431)
		)
	)
	(footprint ""
		(layer "F.Cu")
		(at 169.44848 -423.890948)
		(property "Reference" "R2909"
			(at 0 0 0)
			(layer "F.SilkS")
			(hide yes)
			(effects
				(font
					(size 1.27 1.27)
				)
			)
		)
		(property "Value" ""
			(at 0 0 0)
			(layer "F.Fab")
			(effects
				(font
					(size 1.27 1.27)
				)
			)
		)
		(duplicate_pad_numbers_are_jumpers no)
		(fp_line
			(start -0.7874 -0.4064)
			(end 0.7874 -0.4064)
			(stroke
				(width 0.1524)
				(type default)
			)
			(layer "F.SilkS")
		)
		(fp_line
			(start -0.7874 0.4064)
			(end -0.7874 -0.4064)
			(stroke
				(width 0.1524)
				(type default)
			)
			(layer "F.SilkS")
		)
		(fp_line
			(start 0.7874 -0.4064)
			(end 0.7874 0.4064)
			(stroke
				(width 0.1524)
				(type default)
			)
			(layer "F.SilkS")
		)
		(fp_line
			(start 0.7874 0.4064)
			(end -0.7874 0.4064)
			(stroke
				(width 0.1524)
				(type default)
			)
			(layer "F.SilkS")
		)
		(fp_line
			(start -0.67945 -0.305054)
			(end -0.12065 -0.305054)
			(stroke
				(width 0.1)
				(type default)
			)
			(layer "F.Fab")
		)
		(fp_line
			(start -0.67945 0.3048)
			(end -0.67945 -0.305054)
			(stroke
				(width 0.1)
				(type default)
			)
			(layer "F.Fab")
		)
		(fp_line
			(start -0.12065 -0.305054)
			(end -0.12065 -0.2794)
			(stroke
				(width 0.1)
				(type default)
			)
			(layer "F.Fab")
		)
		(fp_line
			(start -0.12065 -0.2794)
			(end 0.12065 -0.2794)
			(stroke
				(width 0.1)
				(type default)
			)
			(layer "F.Fab")
		)
		(fp_line
			(start -0.12065 0.2794)
			(end -0.12065 0.3048)
			(stroke
				(width 0.1)
				(type default)
			)
			(layer "F.Fab")
		)
		(fp_line
			(start -0.12065 0.3048)
			(end -0.67945 0.3048)
			(stroke
				(width 0.1)
				(type default)
			)
			(layer "F.Fab")
		)
		(fp_line
			(start 0.120396 0.2794)
			(end -0.12065 0.2794)
			(stroke
				(width 0.1)
				(type default)
			)
			(layer "F.Fab")
		)
		(fp_line
			(start 0.120396 0.3048)
			(end 0.120396 0.2794)
			(stroke
				(width 0.1)
				(type default)
			)
			(layer "F.Fab")
		)
		(fp_line
			(start 0.12065 -0.3048)
			(end 0.67945 -0.3048)
			(stroke
				(width 0.1)
				(type default)
			)
			(layer "F.Fab")
		)
		(fp_line
			(start 0.12065 -0.2794)
			(end 0.12065 -0.3048)
			(stroke
				(width 0.1)
				(type default)
			)
			(layer "F.Fab")
		)
		(fp_line
			(start 0.67945 -0.3048)
			(end 0.67945 0.3048)
			(stroke
				(width 0.1)
				(type default)
			)
			(layer "F.Fab")
		)
		(fp_line
			(start 0.67945 0.3048)
			(end 0.120396 0.3048)
			(stroke
				(width 0.1)
				(type default)
			)
			(layer "F.Fab")
		)
		(pad "1" smd circle
			(at -0.40005 0)
			(size 0 0)
			(layers "F.Cu" "F.Mask" "F.Paste")
			(net "P3V3_AUX")
		)
		(pad "2" smd circle
			(at 0.40005 0)
			(size 0 0)
			(layers "F.Cu" "F.Mask" "F.Paste")
			(net "RST_SWB_BIC_R_N")
		)
	)
	(footprint ""
		(layer "F.Cu")
		(at 360.482642 -392.04265)
		(property "Reference" "R4168"
			(at 0 0 0)
			(layer "F.SilkS")
			(hide yes)
			(effects
				(font
					(size 1.27 1.27)
				)
			)
		)
		(property "Value" ""
			(at 0 0 0)
			(layer "F.Fab")
			(effects
				(font
					(size 1.27 1.27)
				)
			)
		)
		(duplicate_pad_numbers_are_jumpers no)
		(fp_line
			(start -0.7874 -0.4064)
			(end 0.7874 -0.4064)
			(stroke
				(width 0.1524)
				(type default)
			)
			(layer "F.SilkS")
		)
		(fp_line
			(start -0.7874 0.4064)
			(end -0.7874 -0.4064)
			(stroke
				(width 0.1524)
				(type default)
			)
			(layer "F.SilkS")
		)
		(fp_line
			(start 0.7874 -0.4064)
			(end 0.7874 0.4064)
			(stroke
				(width 0.1524)
				(type default)
			)
			(layer "F.SilkS")
		)
		(fp_line
			(start 0.7874 0.4064)
			(end -0.7874 0.4064)
			(stroke
				(width 0.1524)
				(type default)
			)
			(layer "F.SilkS")
		)
		(fp_line
			(start -0.67945 -0.305054)
			(end -0.12065 -0.305054)
			(stroke
				(width 0.1)
				(type default)
			)
			(layer "F.Fab")
		)
		(fp_line
			(start -0.67945 0.3048)
			(end -0.67945 -0.305054)
			(stroke
				(width 0.1)
				(type default)
			)
			(layer "F.Fab")
		)
		(fp_line
			(start -0.12065 -0.305054)
			(end -0.12065 -0.2794)
			(stroke
				(width 0.1)
				(type default)
			)
			(layer "F.Fab")
		)
		(fp_line
			(start -0.12065 -0.2794)
			(end 0.12065 -0.2794)
			(stroke
				(width 0.1)
				(type default)
			)
			(layer "F.Fab")
		)
		(fp_line
			(start -0.12065 0.2794)
			(end -0.12065 0.3048)
			(stroke
				(width 0.1)
				(type default)
			)
			(layer "F.Fab")
		)
		(fp_line
			(start -0.12065 0.3048)
			(end -0.67945 0.3048)
			(stroke
				(width 0.1)
				(type default)
			)
			(layer "F.Fab")
		)
		(fp_line
			(start 0.120396 0.2794)
			(end -0.12065 0.2794)
			(stroke
				(width 0.1)
				(type default)
			)
			(layer "F.Fab")
		)
		(fp_line
			(start 0.120396 0.3048)
			(end 0.120396 0.2794)
			(stroke
				(width 0.1)
				(type default)
			)
			(layer "F.Fab")
		)
		(fp_line
			(start 0.12065 -0.3048)
			(end 0.67945 -0.3048)
			(stroke
				(width 0.1)
				(type default)
			)
			(layer "F.Fab")
		)
		(fp_line
			(start 0.12065 -0.2794)
			(end 0.12065 -0.3048)
			(stroke
				(width 0.1)
				(type default)
			)
			(layer "F.Fab")
		)
		(fp_line
			(start 0.67945 -0.3048)
			(end 0.67945 0.3048)
			(stroke
				(width 0.1)
				(type default)
			)
			(layer "F.Fab")
		)
		(fp_line
			(start 0.67945 0.3048)
			(end 0.120396 0.3048)
			(stroke
				(width 0.1)
				(type default)
			)
			(layer "F.Fab")
		)
		(pad "1" smd circle
			(at -0.40005 0)
			(size 0 0)
			(layers "F.Cu" "F.Mask" "F.Paste")
			(net "P3V3_AUX")
		)
		(pad "2" smd circle
			(at 0.40005 0)
			(size 0 0)
			(layers "F.Cu" "F.Mask" "F.Paste")
			(net "GPU_3V3IO_RSVD4_ISO")
		)
	)
	(footprint ""
		(layer "F.Cu")
		(at 55.427118 -408.517344 -90)
		(property "Reference" "C704"
			(at 0 0 270)
			(layer "F.SilkS")
			(hide yes)
			(effects
				(font
					(size 1.27 1.27)
				)
			)
		)
		(property "Value" ""
			(at 0 0 270)
			(layer "F.Fab")
			(effects
				(font
					(size 1.27 1.27)
				)
			)
		)
		(duplicate_pad_numbers_are_jumpers no)
		(fp_line
			(start -0.299974 0.150114)
			(end -0.299974 -0.150114)
			(stroke
				(width 0.1)
				(type default)
			)
			(layer "F.Fab")
		)
		(fp_line
			(start 0.299974 0.150114)
			(end -0.299974 0.150114)
			(stroke
				(width 0.1)
				(type default)
			)
			(layer "F.Fab")
		)
		(fp_line
			(start -0.299974 -0.150114)
			(end 0.299974 -0.150114)
			(stroke
				(width 0.1)
				(type default)
			)
			(layer "F.Fab")
		)
		(fp_line
			(start 0.299974 -0.150114)
			(end 0.299974 0.150114)
			(stroke
				(width 0.1)
				(type default)
			)
			(layer "F.Fab")
		)
		(pad "1" smd rect
			(at -0.2667 0 270)
			(size 0.3048 0.381)
			(layers "F.Cu" "F.Mask" "F.Paste")
			(net "P5E_CPU1_PE4_TX_C_DN<2>")
		)
		(pad "2" smd rect
			(at 0.2667 0 270)
			(size 0.3048 0.381)
			(layers "F.Cu" "F.Mask" "F.Paste")
			(net "P5E_CPU1_PE4_TX_DN<2>")
		)
	)
)
